# BASEBOARD_FAB2 (Tioga Pass) — schematic netlist excerpt (pin names and nets, part order shuffled) for the footprints in the layout excerpt that follows; sources: Cadence DE-HDL packaged netlist, KiCad conversion of Wiwynn_Tioga_Pass_MB.brd

C5D13  CAP  10UF 4V 20% X6S  pkg 0603LF  page 42 : A = PVSA_CPU0 ; B = GND
RT14  RES  0 5.0% CHIP  pkg 0603  page 208 : A = VR_PVCCIN_CPU1_PH4_BOOT ; B = VR_PVCCIN_CPU1_PH4_BOOT_R
R3E1  RES  100.0 1% CHIP  pkg 0402  page 214 : A = VSENSE_PVCCIO_CPU1_AVSP ; B = PVCCIO_CPU1

(kicad_pcb
	(version 20260206)
	(generator "pcbnew")
	(generator_version "10.0")
	(general
		(thickness 1.6)
		(legacy_teardrops no)
	)
	(paper "A4")
	(title_block
		(title "Wiwynn_Tioga_Pass_MB.brd")
		(comment 1 "Tioga Pass / footprints 225-227 of 4770")
	)
	(layers
		(0 "F.Cu" signal "TOP")
		(4 "In1.Cu" signal "L2GND")
		(6 "In2.Cu" signal "L3")
		(8 "In3.Cu" signal "L4GND")
		(10 "In4.Cu" signal "L5")
		(12 "In5.Cu" signal "L6GND")
		(14 "In6.Cu" signal "L7VCC")
		(16 "In7.Cu" signal "L8VCC")
		(18 "In8.Cu" signal "L9GND")
		(20 "In9.Cu" signal "L10")
		(22 "In10.Cu" signal "L11GND")
		(24 "In11.Cu" signal "L12")
		(26 "In12.Cu" signal "L13GND")
		(2 "B.Cu" signal "BOTTOM")
		(9 "F.Adhes" user "F.Adhesive")
		(11 "B.Adhes" user "B.Adhesive")
		(13 "F.Paste" user "Package Geometry/Pastemask Top")
		(15 "B.Paste" user "Package Geometry/Pastemask Bottom")
		(5 "F.SilkS" user "Ref Des/Silkscreen Top")
		(7 "B.SilkS" user "Ref Des/Silkscreen Bottom")
		(1 "F.Mask" user "Board Geometry/Soldermask Top")
		(3 "B.Mask" user "Board Geometry/Soldermask Bottom")
		(17 "Dwgs.User" user "User.Drawings")
		(19 "Cmts.User" user "User.Comments")
		(21 "Eco1.User" user "User.Eco1")
		(23 "Eco2.User" user "User.Eco2")
		(25 "Edge.Cuts" user "Board Geometry/Outline")
		(27 "Margin" user)
		(31 "F.CrtYd" user "Package Geometry/Place Bound Top")
		(29 "B.CrtYd" user "Package Geometry/Place Bound Bottom")
		(35 "F.Fab" user "Ref Des/Assembly Top")
		(33 "B.Fab" user "Ref Des/Assembly Bottom")
	)
	(footprint ""
		(layer "F.Cu")
		(at 258.208272 -81.560416)
		(property "Reference" "C5D13"
			(at 0 0 0)
			(layer "F.SilkS")
			(hide yes)
			(effects
				(font
					(size 1.27 1.27)
				)
			)
		)
		(property "Value" ""
			(at 0 0 0)
			(layer "F.Fab")
			(effects
				(font
					(size 1.27 1.27)
				)
			)
		)
		(duplicate_pad_numbers_are_jumpers no)
		(fp_poly
			(pts
				(xy -0.4953 -0.2032) (xy 0.4953 -0.2032) (xy 0.4953 1.6002) (xy -0.4953 1.6002)
			)
			(stroke
				(width 0)
				(type default)
			)
			(fill no)
			(layer "F.CrtYd")
		)
		(fp_line
			(start -0.4953 -0.2032)
			(end 0.4953 -0.2032)
			(stroke
				(width 0.1)
				(type default)
			)
			(layer "F.Fab")
		)
		(fp_line
			(start -0.4953 1.6002)
			(end -0.4953 -0.2032)
			(stroke
				(width 0.1)
				(type default)
			)
			(layer "F.Fab")
		)
		(fp_line
			(start 0.4953 -0.2032)
			(end 0.4953 1.6002)
			(stroke
				(width 0.1)
				(type default)
			)
			(layer "F.Fab")
		)
		(fp_line
			(start 0.4953 1.6002)
			(end -0.4953 1.6002)
			(stroke
				(width 0.1)
				(type default)
			)
			(layer "F.Fab")
		)
		(pad "1" smd rect
			(at 0 0)
			(size 0.762 0.889)
			(layers "F.Cu" "F.Mask" "F.Paste")
			(net "PVSA_CPU0")
		)
		(pad "2" smd rect
			(at 0 1.397)
			(size 0.762 0.889)
			(layers "F.Cu" "F.Mask" "F.Paste")
			(net "GND")
		)
		(zone
			(layer "F.Cu")
			(hatch none 0.5)
			(connect_pads
				(clearance 0)
			)
			(min_thickness 0.25)
			(keepout
				(tracks not_allowed)
				(vias allowed)
				(pads allowed)
				(copperpour not_allowed)
				(footprints allowed)
			)
			(placement
				(enabled no)
				(sheetname "")
			)
			(fill
				(thermal_gap 0.5)
				(thermal_bridge_width 0.5)
				(island_removal_mode 0)
			)
			(polygon
				(pts
					(xy 257.827272 -81.115916) (xy 258.589272 -81.115916) (xy 258.589272 -80.607916) (xy 257.827272 -80.607916)
				)
			)
		)
	)
	(footprint ""
		(layer "F.Cu")
		(at 162.871912 -63.829184)
		(property "Reference" "R3E1"
			(at 0 0 0)
			(layer "F.SilkS")
			(hide yes)
			(effects
				(font
					(size 1.27 1.27)
				)
			)
		)
		(property "Value" ""
			(at 0 0 0)
			(layer "F.Fab")
			(effects
				(font
					(size 1.27 1.27)
				)
			)
		)
		(duplicate_pad_numbers_are_jumpers no)
		(fp_poly
			(pts
				(xy -0.2794 -0.1016) (xy 0.2794 -0.1016) (xy 0.2794 0.9906) (xy -0.2794 0.9906)
			)
			(stroke
				(width 0)
				(type default)
			)
			(fill no)
			(layer "F.CrtYd")
		)
		(fp_line
			(start -0.2794 -0.1016)
			(end -0.2794 0.9906)
			(stroke
				(width 0.1)
				(type default)
			)
			(layer "F.Fab")
		)
		(fp_line
			(start -0.2794 0.9906)
			(end 0.2794 0.9906)
			(stroke
				(width 0.1)
				(type default)
			)
			(layer "F.Fab")
		)
		(fp_line
			(start 0.2794 -0.1016)
			(end -0.2794 -0.1016)
			(stroke
				(width 0.1)
				(type default)
			)
			(layer "F.Fab")
		)
		(fp_line
			(start 0.2794 0.9906)
			(end 0.2794 -0.1016)
			(stroke
				(width 0.1)
				(type default)
			)
			(layer "F.Fab")
		)
		(pad "1" smd rect
			(at 0 0)
			(size 0.508 0.508)
			(layers "F.Cu" "F.Mask" "F.Paste")
			(net "VSENSE_PVCCIO_CPU1_AVSP")
		)
		(pad "2" smd rect
			(at 0 0.889)
			(size 0.508 0.508)
			(layers "F.Cu" "F.Mask" "F.Paste")
			(net "PVCCIO_CPU1")
		)
		(zone
			(layer "F.Cu")
			(hatch none 0.5)
			(connect_pads
				(clearance 0)
			)
			(min_thickness 0.25)
			(keepout
				(tracks allowed)
				(vias not_allowed)
				(pads allowed)
				(copperpour not_allowed)
				(footprints allowed)
			)
			(placement
				(enabled no)
				(sheetname "")
			)
			(fill
				(thermal_gap 0.5)
				(thermal_bridge_width 0.5)
				(island_removal_mode 0)
			)
			(polygon
				(pts
					(xy 162.617912 -63.575184) (xy 163.125912 -63.575184) (xy 163.125912 -63.194184) (xy 162.617912 -63.194184)
				)
			)
		)
		(zone
			(layer "F.Cu")
			(hatch none 0.5)
			(connect_pads
				(clearance 0)
			)
			(min_thickness 0.25)
			(keepout
				(tracks not_allowed)
				(vias allowed)
				(pads allowed)
				(copperpour not_allowed)
				(footprints allowed)
			)
			(placement
				(enabled no)
				(sheetname "")
			)
			(fill
				(thermal_gap 0.5)
				(thermal_bridge_width 0.5)
				(island_removal_mode 0)
			)
			(polygon
				(pts
					(xy 162.617912 -63.194184) (xy 163.125912 -63.194184) (xy 163.125912 -63.575184) (xy 162.617912 -63.575184)
				)
			)
		)
	)
	(footprint ""
		(layer "F.Cu")
		(at 27.4828 -81.915 90)
		(property "Reference" "RT14"
			(at 1.01473 0.656336 0)
			(unlocked yes)
			(layer "F.SilkS")
			(effects
				(font
					(size 0.4064 0.254)
					(thickness 0.1524)
				)
			)
		)
		(property "Value" ""
			(at 0 0 90)
			(layer "F.Fab")
			(effects
				(font
					(size 1.27 1.27)
				)
			)
		)
		(duplicate_pad_numbers_are_jumpers no)
		(fp_poly
			(pts
				(xy -0.4953 -0.2032) (xy 0.4953 -0.2032) (xy 0.4953 1.6002) (xy -0.4953 1.6002)
			)
			(stroke
				(width 0)
				(type default)
			)
			(fill no)
			(layer "F.CrtYd")
		)
		(fp_line
			(start 0.4953 -0.2032)
			(end 0.4953 1.6002)
			(stroke
				(width 0.1)
				(type default)
			)
			(layer "F.Fab")
		)
		(fp_line
			(start -0.4953 -0.2032)
			(end 0.4953 -0.2032)
			(stroke
				(width 0.1)
				(type default)
			)
			(layer "F.Fab")
		)
		(fp_line
			(start 0.4953 1.6002)
			(end -0.4953 1.6002)
			(stroke
				(width 0.1)
				(type default)
			)
			(layer "F.Fab")
		)
		(fp_line
			(start -0.4953 1.6002)
			(end -0.4953 -0.2032)
			(stroke
				(width 0.1)
				(type default)
			)
			(layer "F.Fab")
		)
		(pad "1" smd rect
			(at 0 0 90)
			(size 0.762 0.889)
			(layers "F.Cu" "F.Mask" "F.Paste")
			(net "VR_PVCCIN_CPU1_PH4_BOOT")
		)
		(pad "2" smd rect
			(at 0 1.397 90)
			(size 0.762 0.889)
			(layers "F.Cu" "F.Mask" "F.Paste")
			(net "VR_PVCCIN_CPU1_PH4_BOOT_R")
		)
		(zone
			(layer "F.Cu")
			(hatch none 0.5)
			(connect_pads
				(clearance 0)
			)
			(min_thickness 0.25)
			(keepout
				(tracks allowed)
				(vias not_allowed)
				(pads allowed)
				(copperpour not_allowed)
				(footprints allowed)
			)
			(placement
				(enabled no)
				(sheetname "")
			)
			(fill
				(thermal_gap 0.5)
				(thermal_bridge_width 0.5)
				(island_removal_mode 0)
			)
			(polygon
				(pts
					(xy 28.4353 -82.296) (xy 27.9273 -82.296) (xy 27.9273 -81.534) (xy 28.4353 -81.534)
				)
			)
		)
		(zone
			(layer "F.Cu")
			(hatch none 0.5)
			(connect_pads
				(clearance 0)
			)
			(min_thickness 0.25)
			(keepout
				(tracks not_allowed)
				(vias allowed)
				(pads allowed)
				(copperpour not_allowed)
				(footprints allowed)
			)
			(placement
				(enabled no)
				(sheetname "")
			)
			(fill
				(thermal_gap 0.5)
				(thermal_bridge_width 0.5)
				(island_removal_mode 0)
			)
			(polygon
				(pts
					(xy 28.4353 -81.534) (xy 28.4353 -82.296) (xy 27.9273 -82.296) (xy 27.9273 -81.534)
				)
			)
		)
	)
)
